# BASEBOARD_FAB2 (Tioga Pass) — schematic netlist excerpt (pin names and nets, part order shuffled) for the footprints in the layout excerpt that follows; sources: Cadence DE-HDL packaged netlist, KiCad conversion of Wiwynn_Tioga_Pass_MB.brd

J6L2  SCONN288_H44441003  SCONN  pkg PIP  page 52
  \12v\(1)  = P12V_NVDIMM_DEF
  VSS(93)  = GND
  DQ(4)  = M_E_DQ<4>
  VSS(92)  = GND
  DQ(0)  = M_E_DQ<0>
  VSS(91)  = GND
  DQS9P  = M_E_DQS_DP<9>
  DQS9N  = M_E_DQS_DN<9>
  VSS(90)  = GND
  DQ(6)  = M_E_DQ<6>
  VSS(89)  = GND
  DQ(2)  = M_E_DQ<2>
  VSS(88)  = GND
  DQ(12)  = M_E_DQ<12>
  VSS(87)  = GND
  DQ(8)  = M_E_DQ<8>
  VSS(86)  = GND
  DQS10P  = M_E_DQS_DP<10>
  DQS10N  = M_E_DQS_DN<10>
  VSS(85)  = GND
  DQ(14)  = M_E_DQ<14>
  VSS(84)  = GND
  DQ(10)  = M_E_DQ<10>
  VSS(83)  = GND
  DQ(20)  = M_E_DQ<20>
  VSS(82)  = GND
  DQ(16)  = M_E_DQ<16>
  VSS(81)  = GND
  DQS11P  = M_E_DQS_DP<11>
  DQS11N  = M_E_DQS_DN<11>
  VSS(80)  = GND
  DQ(22)  = M_E_DQ<22>
  VSS(79)  = GND
  DQ(18)  = M_E_DQ<18>
  VSS(78)  = GND
  DQ(28)  = M_E_DQ<28>
  VSS(77)  = GND
  DQ(24)  = M_E_DQ<24>
  VSS(76)  = GND
  DQS12P  = M_E_DQS_DP<12>
  DQS12N  = M_E_DQS_DN<12>
  VSS(75)  = GND
  DQ(30)  = M_E_DQ<30>
  VSS(74)  = GND
  DQ(26)  = M_E_DQ<26>
  VSS(73)  = GND
  CB(4)  = M_E_ECC<4>
  VSS(72)  = GND
  CB(0)  = M_E_ECC<0>
  VSS(71)  = GND
  DQS17P  = M_E_DQS_DP<17>
  DQS17N  = M_E_DQS_DN<17>
  VSS(70)  = GND
  CB(6)  = M_E_ECC<6>
  VSS(69)  = GND
  CB(2)  = M_E_ECC<2>
  VSS(68)  = GND
  RESET_N  = M_DEF_RST_N
  VDD(25)  = PVDDQ_DEF
  CKE(0)  = M_E_CKE<2>
  VDD(24)  = PVDDQ_DEF
  ACT_N  = M_E_ACT_N
  BG(0)  = M_E_BG<0>
  VDD(23)  = PVDDQ_DEF
  A12  = M_E_MA<12>
  A9  = M_E_MA<9>
  VDD(22)  = PVDDQ_DEF
  A8  = M_E_MA<8>
  A6  = M_E_MA<6>
  VDD(21)  = PVDDQ_DEF
  A3  = M_E_MA<3>
  A1  = M_E_MA<1>
  VDD(20)  = PVDDQ_DEF
  CK0P  = M_E_CLK_DP<2>
  CK0N  = M_E_CLK_DN<2>
  VDD(19)  = PVDDQ_DEF
  VTT(1)  = PVTT_DEF
  EVENT_N  = FM_DIMM_EVENT_COD_N
  A0  = M_E_MA<0>
  VDD(18)  = PVDDQ_DEF
  BA(0)  = M_E_BA<0>
  A16_RAS_N  = M_E_MA<16>
  VDD(17)  = PVDDQ_DEF
  S0_N  = M_E_CS_N<4>
  VDD(16)  = PVDDQ_DEF
  A15_CAS_N  = M_E_MA<15>
  ODT(0)  = M_E_ODT<2>
  VDD(15)  = PVDDQ_DEF
  S1_N  = M_E_CS_N<5>
  VDD(14)  = PVDDQ_DEF
  ODT(1)  = M_E_ODT<3>
  VDD(13)  = PVDDQ_DEF
  S2_N_C(0)  = M_E_CS_N<6>
  VSS(67)  = GND
  DQ(36)  = M_E_DQ<36>
  VSS(66)  = GND
  DQ(32)  = M_E_DQ<32>
  VSS(65)  = GND
  DQS13P  = M_E_DQS_DP<13>
  DQS13N  = M_E_DQS_DN<13>
  VSS(64)  = GND
  DQ(38)  = M_E_DQ<38>
  VSS(63)  = GND
  DQ(34)  = M_E_DQ<34>
  VSS(62)  = GND
  DQ(44)  = M_E_DQ<44>
  VSS(61)  = GND
  DQ(40)  = M_E_DQ<40>
  VSS(60)  = GND
  DQS14P  = M_E_DQS_DP<14>
  DQS14N  = M_E_DQS_DN<14>
  VSS(59)  = GND
  DQ(46)  = M_E_DQ<46>
  VSS(58)  = GND
  DQ(42)  = M_E_DQ<42>
  VSS(57)  = GND
  DQ(52)  = M_E_DQ<52>
  VSS(56)  = GND
  DQ(48)  = M_E_DQ<48>
  VSS(55)  = GND
  DQS15P  = M_E_DQS_DP<15>
  DQS15N  = M_E_DQS_DN<15>
  VSS(54)  = GND
  DQ(54)  = M_E_DQ<54>
  VSS(53)  = GND
  DQ(50)  = M_E_DQ<50>
  VSS(52)  = GND
  DQ(60)  = M_E_DQ<60>
  VSS(51)  = GND
  DQ(56)  = M_E_DQ<56>
  VSS(50)  = GND
  DQS16P  = M_E_DQS_DP<16>
  DQS16N  = M_E_DQS_DN<16>
  VSS(49)  = GND
  DQ(62)  = M_E_DQ<62>
  VSS(48)  = GND
  DQ(58)  = M_E_DQ<58>
  VSS(47)  = GND
  SA(0)  = PVPP_DEF
  SA(1)  = PVPP_DEF
  SCL  = SMB_DDR_DEF_VPP_SCL
  VPP(4)  = PVPP_DEF
  VPP(3)  = PVPP_DEF
  RFU(2)  = TP_CH_E_DIMM_E1_RFU_2
  \12v\(0)  = P12V_NVDIMM_DEF
  VREFCA  = M_E_VREF
  VSS(46)  = GND
  DQ(5)  = M_E_DQ<5>
  VSS(45)  = GND
  DQ(1)  = M_E_DQ<1>
  VSS(44)  = GND
  DQS0N  = M_E_DQS_DN<0>
  DQS0P  = M_E_DQS_DP<0>
  VSS(43)  = GND
  DQ(7)  = M_E_DQ<7>
  VSS(42)  = GND
  DQ(3)  = M_E_DQ<3>
  VSS(41)  = GND
  DQ(13)  = M_E_DQ<13>
  VSS(40)  = GND
  DQ(9)  = M_E_DQ<9>
  VSS(39)  = GND
  DQS1N  = M_E_DQS_DN<1>
  DQS1P  = M_E_DQS_DP<1>
  VSS(38)  = GND
  DQ(15)  = M_E_DQ<15>
  VSS(37)  = GND
  DQ(11)  = M_E_DQ<11>
  VSS(36)  = GND
  DQ(21)  = M_E_DQ<21>
  VSS(35)  = GND
  DQ(17)  = M_E_DQ<17>
  VSS(34)  = GND
  DQS2N  = M_E_DQS_DN<2>
  DQS2P  = M_E_DQS_DP<2>
  VSS(33)  = GND
  DQ(23)  = M_E_DQ<23>
  VSS(32)  = GND
  DQ(19)  = M_E_DQ<19>
  VSS(31)  = GND
  DQ(29)  = M_E_DQ<29>
  VSS(30)  = GND
  DQ(25)  = M_E_DQ<25>
  VSS(29)  = GND
  DQS3N  = M_E_DQS_DN<3>
  DQS3P  = M_E_DQS_DP<3>
  VSS(28)  = GND
  DQ(31)  = M_E_DQ<31>
  VSS(27)  = GND
  DQ(27)  = M_E_DQ<27>
  VSS(26)  = GND
  CB(5)  = M_E_ECC<5>
  VSS(25)  = GND
  CB(1)  = M_E_ECC<1>
  VSS(24)  = GND
  DQS8N  = M_E_DQS_DN<8>
  DQS8P  = M_E_DQS_DP<8>
  VSS(23)  = GND
  CB(7)  = M_E_ECC<7>
  VSS(22)  = GND
  CB(3)  = M_E_ECC<3>
  VSS(21)  = GND
  CKE(1)  = M_E_CKE<3>
  VDD(12)  = PVDDQ_DEF
  RFU(0)  = TP_CH_E_DIMM_E1_RFU_0
  VDD(11)  = PVDDQ_DEF
  BG(1)  = M_E_BG<1>
  ALERT_N  = M_E_ALERT_N
  VDD(10)  = PVDDQ_DEF
  A11  = M_E_MA<11>
  A7  = M_E_MA<7>
  VDD(9)  = PVDDQ_DEF
  A5  = M_E_MA<5>
  A4  = M_E_MA<4>
  VDD(8)  = PVDDQ_DEF
  A2  = M_E_MA<2>
  VDD(7)  = PVDDQ_DEF
  CK1P  = M_E_CLK_DP<3>
  CK1N  = M_E_CLK_DN<3>
  VDD(6)  = PVDDQ_DEF
  VTT(0)  = PVTT_DEF
  PAR  = M_E_PAR
  VDD(5)  = PVDDQ_DEF
  BA(1)  = M_E_BA<1>
  A10  = M_E_MA<10>
  VDD(4)  = PVDDQ_DEF
  RFU(1)  = TP_CH_E_DIMM_E1_RFU_1
  A14_WE_N  = M_E_MA<14>
  VDD(3)  = PVDDQ_DEF
  SAVE_N_NC  = FM_ADR_COMPLETE_DEF_N
  VDD(2)  = PVDDQ_DEF
  A13  = M_E_MA<13>
  VDD(1)  = PVDDQ_DEF
  A17  = M_E_MA<17>
  C(2)  = M_E_C<2>
  VDD(0)  = PVDDQ_DEF
  S3_N_C(1)  = M_E_CS_N<7>
  SA(2)  = GND
  VSS(20)  = GND
  DQ(37)  = M_E_DQ<37>
  VSS(19)  = GND
  DQ(33)  = M_E_DQ<33>
  VSS(18)  = GND
  DQS4N  = M_E_DQS_DN<4>
  DQS4P  = M_E_DQS_DP<4>
  VSS(17)  = GND
  DQ(39)  = M_E_DQ<39>
  VSS(16)  = GND
  DQ(35)  = M_E_DQ<35>
  VSS(15)  = GND
  DQ(45)  = M_E_DQ<45>
  VSS(14)  = GND
  DQ(41)  = M_E_DQ<41>
  VSS(13)  = GND
  DQS5N  = M_E_DQS_DN<5>
  DQS5P  = M_E_DQS_DP<5>
  VSS(12)  = GND
  DQ(47)  = M_E_DQ<47>
  VSS(11)  = GND
  DQ(43)  = M_E_DQ<43>
  VSS(10)  = GND
  DQ(53)  = M_E_DQ<53>
  VSS(9)  = GND
  DQ(49)  = M_E_DQ<49>
  VSS(8)  = GND
  DQS6N  = M_E_DQS_DN<6>
  DQS6P  = M_E_DQS_DP<6>
  VSS(7)  = GND
  DQ(55)  = M_E_DQ<55>
  VSS(6)  = GND
  DQ(51)  = M_E_DQ<51>
  VSS(5)  = GND
  DQ(61)  = M_E_DQ<61>
  VSS(4)  = GND
  DQ(57)  = M_E_DQ<57>
  VSS(3)  = GND
  DQS7N  = M_E_DQS_DN<7>
  DQS7P  = M_E_DQS_DP<7>
  VSS(2)  = GND
  DQ(63)  = M_E_DQ<63>
  VSS(1)  = GND
  DQ(59)  = M_E_DQ<59>
  VSS(0)  = GND
  VDDSPD  = PVPP_DEF
  SDA  = SMB_DDR_DEF_VPP_SDA
  VPP(1)  = PVPP_DEF
  VPP(0)  = PVPP_DEF
  VPP(2)  = PVPP_DEF

(kicad_pcb
	(version 20260206)
	(generator "pcbnew")
	(generator_version "10.0")
	(general
		(thickness 1.6)
		(legacy_teardrops no)
	)
	(paper "A4")
	(title_block
		(title "Wiwynn_Tioga_Pass_MB.brd")
		(comment 1 "Tioga Pass / footprint 3319 of 4770 (J6L2), pads 1-50 of 291")
	)
	(layers
		(0 "F.Cu" signal "TOP")
		(4 "In1.Cu" signal "L2GND")
		(6 "In2.Cu" signal "L3")
		(8 "In3.Cu" signal "L4GND")
		(10 "In4.Cu" signal "L5")
		(12 "In5.Cu" signal "L6GND")
		(14 "In6.Cu" signal "L7VCC")
		(16 "In7.Cu" signal "L8VCC")
		(18 "In8.Cu" signal "L9GND")
		(20 "In9.Cu" signal "L10")
		(22 "In10.Cu" signal "L11GND")
		(24 "In11.Cu" signal "L12")
		(26 "In12.Cu" signal "L13GND")
		(2 "B.Cu" signal "BOTTOM")
		(9 "F.Adhes" user "F.Adhesive")
		(11 "B.Adhes" user "B.Adhesive")
		(13 "F.Paste" user "Package Geometry/Pastemask Top")
		(15 "B.Paste" user "Package Geometry/Pastemask Bottom")
		(5 "F.SilkS" user "Ref Des/Silkscreen Top")
		(7 "B.SilkS" user "Ref Des/Silkscreen Bottom")
		(1 "F.Mask" user "Board Geometry/Soldermask Top")
		(3 "B.Mask" user "Board Geometry/Soldermask Bottom")
		(17 "Dwgs.User" user "User.Drawings")
		(19 "Cmts.User" user "User.Comments")
		(21 "Eco1.User" user "User.Eco1")
		(23 "Eco2.User" user "User.Eco2")
		(25 "Edge.Cuts" user "Board Geometry/Outline")
		(27 "Margin" user)
		(31 "F.CrtYd" user "Package Geometry/Place Bound Top")
		(29 "B.CrtYd" user "Package Geometry/Place Bound Bottom")
		(35 "F.Fab" user "Ref Des/Assembly Top")
		(33 "B.Fab" user "Ref Des/Assembly Bottom")
	)
	(footprint ""
		(layer "B.Cu")
		(at 194.700398 -142.477236 90)
		(property "Reference" "J6L2"
			(at 2.276348 38.21811 0)
			(unlocked yes)
			(layer "B.SilkS")
			(effects
				(font
					(size 0.7874 0.5842)
					(thickness 0.1524)
				)
				(justify left mirror)
			)
		)
		(property "Value" ""
			(at 0 0 90)
			(layer "B.Fab")
			(effects
				(font
					(size 1.27 1.27)
				)
				(justify mirror)
			)
		)
		(duplicate_pad_numbers_are_jumpers no)
		(pad "" thru_hole circle
			(at -2.29997 -5.649976 270)
			(size 2.8194 2.8194)
			(drill 2.4384)
			(layers "*.Cu" "*.Mask")
			(remove_unused_layers no)
			(clearance 0.127)
			(thermal_gap 0.127)
		)
		(pad "" thru_hole oval
			(at -2.29997 68.90004 270)
			(size 2.8194 1.5748)
			(drill oval 2.4384 1.1938)
			(layers "*.Cu" "*.Mask")
			(remove_unused_layers no)
			(clearance 0.127)
			(thermal_gap 0.127)
		)
		(pad "" thru_hole circle
			(at -2.29997 132.299964 270)
			(size 2.8194 2.8194)
			(drill 2.4384)
			(layers "*.Cu" "*.Mask")
			(remove_unused_layers no)
			(clearance 0.127)
			(thermal_gap 0.127)
		)
		(pad "1" smd rect
			(at 0 0 270)
			(size 1.8034 0.508)
			(layers "B.Cu" "B.Mask" "B.Paste")
			(net "P12V_NVDIMM_DEF")
		)
		(pad "2" smd rect
			(at 0 0.849884 270)
			(size 1.8034 0.508)
			(layers "B.Cu" "B.Mask" "B.Paste")
			(net "GND")
		)
		(pad "3" smd rect
			(at 0 1.700022 270)
			(size 1.8034 0.508)
			(layers "B.Cu" "B.Mask" "B.Paste")
			(net "M_E_DQ<4>")
		)
		(pad "4" smd rect
			(at 0 2.549906 270)
			(size 1.8034 0.508)
			(layers "B.Cu" "B.Mask" "B.Paste")
			(net "GND")
		)
		(pad "5" smd rect
			(at 0 3.400044 270)
			(size 1.8034 0.508)
			(layers "B.Cu" "B.Mask" "B.Paste")
			(net "M_E_DQ<0>")
		)
		(pad "6" smd rect
			(at 0 4.249928 270)
			(size 1.8034 0.508)
			(layers "B.Cu" "B.Mask" "B.Paste")
			(net "GND")
		)
		(pad "7" smd rect
			(at 0 5.100066 270)
			(size 1.8034 0.508)
			(layers "B.Cu" "B.Mask" "B.Paste")
			(net "M_E_DQS_DP<9>")
		)
		(pad "8" smd rect
			(at 0 5.94995 270)
			(size 1.8034 0.508)
			(layers "B.Cu" "B.Mask" "B.Paste")
			(net "M_E_DQS_DN<9>")
		)
		(pad "9" smd rect
			(at 0 6.800088 270)
			(size 1.8034 0.508)
			(layers "B.Cu" "B.Mask" "B.Paste")
			(net "GND")
		)
		(pad "10" smd rect
			(at 0 7.649972 270)
			(size 1.8034 0.508)
			(layers "B.Cu" "B.Mask" "B.Paste")
			(net "M_E_DQ<6>")
		)
		(pad "11" smd rect
			(at 0 8.50011 270)
			(size 1.8034 0.508)
			(layers "B.Cu" "B.Mask" "B.Paste")
			(net "GND")
		)
		(pad "12" smd rect
			(at 0 9.349994 270)
			(size 1.8034 0.508)
			(layers "B.Cu" "B.Mask" "B.Paste")
			(net "M_E_DQ<2>")
		)
		(pad "13" smd rect
			(at 0 10.199878 270)
			(size 1.8034 0.508)
			(layers "B.Cu" "B.Mask" "B.Paste")
			(net "GND")
		)
		(pad "14" smd rect
			(at 0 11.050016 270)
			(size 1.8034 0.508)
			(layers "B.Cu" "B.Mask" "B.Paste")
			(net "M_E_DQ<12>")
		)
		(pad "15" smd rect
			(at 0 11.8999 270)
			(size 1.8034 0.508)
			(layers "B.Cu" "B.Mask" "B.Paste")
			(net "GND")
		)
		(pad "16" smd rect
			(at 0 12.750038 270)
			(size 1.8034 0.508)
			(layers "B.Cu" "B.Mask" "B.Paste")
			(net "M_E_DQ<8>")
		)
		(pad "17" smd rect
			(at 0 13.599922 270)
			(size 1.8034 0.508)
			(layers "B.Cu" "B.Mask" "B.Paste")
			(net "GND")
		)
		(pad "18" smd rect
			(at 0 14.45006 270)
			(size 1.8034 0.508)
			(layers "B.Cu" "B.Mask" "B.Paste")
			(net "M_E_DQS_DP<10>")
		)
		(pad "19" smd rect
			(at 0 15.299944 270)
			(size 1.8034 0.508)
			(layers "B.Cu" "B.Mask" "B.Paste")
			(net "M_E_DQS_DN<10>")
		)
		(pad "20" smd rect
			(at 0 16.150082 270)
			(size 1.8034 0.508)
			(layers "B.Cu" "B.Mask" "B.Paste")
			(net "GND")
		)
		(pad "21" smd rect
			(at 0 16.999966 270)
			(size 1.8034 0.508)
			(layers "B.Cu" "B.Mask" "B.Paste")
			(net "M_E_DQ<14>")
		)
		(pad "22" smd rect
			(at 0 17.850104 270)
			(size 1.8034 0.508)
			(layers "B.Cu" "B.Mask" "B.Paste")
			(net "GND")
		)
		(pad "23" smd rect
			(at 0 18.699988 270)
			(size 1.8034 0.508)
			(layers "B.Cu" "B.Mask" "B.Paste")
			(net "M_E_DQ<10>")
		)
		(pad "24" smd rect
			(at 0 19.550126 270)
			(size 1.8034 0.508)
			(layers "B.Cu" "B.Mask" "B.Paste")
			(net "GND")
		)
		(pad "25" smd rect
			(at 0 20.40001 270)
			(size 1.8034 0.508)
			(layers "B.Cu" "B.Mask" "B.Paste")
			(net "M_E_DQ<20>")
		)
		(pad "26" smd rect
			(at 0 21.249894 270)
			(size 1.8034 0.508)
			(layers "B.Cu" "B.Mask" "B.Paste")
			(net "GND")
		)
		(pad "27" smd rect
			(at 0 22.100032 270)
			(size 1.8034 0.508)
			(layers "B.Cu" "B.Mask" "B.Paste")
			(net "M_E_DQ<16>")
		)
		(pad "28" smd rect
			(at 0 22.949916 270)
			(size 1.8034 0.508)
			(layers "B.Cu" "B.Mask" "B.Paste")
			(net "GND")
		)
		(pad "29" smd rect
			(at 0 23.800054 270)
			(size 1.8034 0.508)
			(layers "B.Cu" "B.Mask" "B.Paste")
			(net "M_E_DQS_DP<11>")
		)
		(pad "30" smd rect
			(at 0 24.649938 270)
			(size 1.8034 0.508)
			(layers "B.Cu" "B.Mask" "B.Paste")
			(net "M_E_DQS_DN<11>")
		)
		(pad "31" smd rect
			(at 0 25.500076 270)
			(size 1.8034 0.508)
			(layers "B.Cu" "B.Mask" "B.Paste")
			(net "GND")
		)
		(pad "32" smd rect
			(at 0 26.34996 270)
			(size 1.8034 0.508)
			(layers "B.Cu" "B.Mask" "B.Paste")
			(net "M_E_DQ<22>")
		)
		(pad "33" smd rect
			(at 0 27.200098 270)
			(size 1.8034 0.508)
			(layers "B.Cu" "B.Mask" "B.Paste")
			(net "GND")
		)
		(pad "34" smd rect
			(at 0 28.049982 270)
			(size 1.8034 0.508)
			(layers "B.Cu" "B.Mask" "B.Paste")
			(net "M_E_DQ<18>")
		)
		(pad "35" smd rect
			(at 0 28.90012 270)
			(size 1.8034 0.508)
			(layers "B.Cu" "B.Mask" "B.Paste")
			(net "GND")
		)
		(pad "36" smd rect
			(at 0 29.750004 270)
			(size 1.8034 0.508)
			(layers "B.Cu" "B.Mask" "B.Paste")
			(net "M_E_DQ<28>")
		)
		(pad "37" smd rect
			(at 0 30.599888 270)
			(size 1.8034 0.508)
			(layers "B.Cu" "B.Mask" "B.Paste")
			(net "GND")
		)
		(pad "38" smd rect
			(at 0 31.450026 270)
			(size 1.8034 0.508)
			(layers "B.Cu" "B.Mask" "B.Paste")
			(net "M_E_DQ<24>")
		)
		(pad "39" smd rect
			(at 0 32.29991 270)
			(size 1.8034 0.508)
			(layers "B.Cu" "B.Mask" "B.Paste")
			(net "GND")
		)
		(pad "40" smd rect
			(at 0 33.150048 270)
			(size 1.8034 0.508)
			(layers "B.Cu" "B.Mask" "B.Paste")
			(net "M_E_DQS_DP<12>")
		)
		(pad "41" smd rect
			(at 0 33.999932 270)
			(size 1.8034 0.508)
			(layers "B.Cu" "B.Mask" "B.Paste")
			(net "M_E_DQS_DN<12>")
		)
		(pad "42" smd rect
			(at 0 34.85007 270)
			(size 1.8034 0.508)
			(layers "B.Cu" "B.Mask" "B.Paste")
			(net "GND")
		)
		(pad "43" smd rect
			(at 0 35.699954 270)
			(size 1.8034 0.508)
			(layers "B.Cu" "B.Mask" "B.Paste")
			(net "M_E_DQ<30>")
		)
		(pad "44" smd rect
			(at 0 36.550092 270)
			(size 1.8034 0.508)
			(layers "B.Cu" "B.Mask" "B.Paste")
			(net "GND")
		)
		(pad "45" smd rect
			(at 0 37.399976 270)
			(size 1.8034 0.508)
			(layers "B.Cu" "B.Mask" "B.Paste")
			(net "M_E_DQ<26>")
		)
		(pad "46" smd rect
			(at 0 38.250114 270)
			(size 1.8034 0.508)
			(layers "B.Cu" "B.Mask" "B.Paste")
			(net "GND")
		)
		(pad "47" smd rect
			(at 0 39.099998 270)
			(size 1.8034 0.508)
			(layers "B.Cu" "B.Mask" "B.Paste")
			(net "M_E_ECC<4>")
		)
	)
)
